(kicad_pcb
	(version 20240108)
	(generator "pcbnew")
	(generator_version "8.0")
	(general
		(thickness 1.6)
		(legacy_teardrops no)
	)
	(paper "A4")
	(title_block
		(title "Jetson Orin Baseboard OCuLink Expansion")
		(date "2025-03-18")
		(rev "1.1.0")
		(company "Antmicro Ltd")
		(comment 1 "www.antmicro.com")
		(comment 9 "footprints 25-26 of 119")
	)
	(layers
		(0 "F.Cu" signal)
		(1 "In1.Cu" signal)
		(2 "In2.Cu" signal)
		(31 "B.Cu" signal)
		(32 "B.Adhes" user "B.Adhesive")
		(33 "F.Adhes" user "F.Adhesive")
		(34 "B.Paste" user)
		(35 "F.Paste" user)
		(36 "B.SilkS" user "B.Silkscreen")
		(37 "F.SilkS" user "F.Silkscreen")
		(38 "B.Mask" user)
		(39 "F.Mask" user)
		(40 "Dwgs.User" user "User.Drawings")
		(41 "Cmts.User" user "User.Comments")
		(42 "Eco1.User" user "User.Eco1")
		(43 "Eco2.User" user "User.Eco2")
		(44 "Edge.Cuts" user)
		(45 "Margin" user)
		(46 "B.CrtYd" user "B.Courtyard")
		(47 "F.CrtYd" user "F.Courtyard")
		(48 "B.Fab" user)
		(49 "F.Fab" user)
	)
	(footprint "antmicro-footprints:Amphenol_G14A421211112HR"
		(layer "F.Cu")
		(at 119.92875 146.930466)
		(property "Reference" "J1"
			(at -9.52875 -4.330466 0)
			(unlocked yes)
			(layer "F.SilkS")
			(effects
				(font
					(size 0.7 0.7)
					(thickness 0.15)
				)
				(justify left bottom)
			)
		)
		(property "Value" "OCuLink_x4_Amphenol_G14A421211112HR"
			(at 0 6.385 0)
			(unlocked yes)
			(layer "F.Fab")
			(effects
				(font
					(size 0.7 0.7)
					(thickness 0.15)
				)
				(justify left bottom)
			)
		)
		(property "Footprint" "antmicro-footprints:Amphenol_G14A421211112HR"
			(at 0 0 0)
			(layer "F.Fab")
			(hide yes)
			(effects
				(font
					(size 1.27 1.27)
					(thickness 0.15)
				)
			)
		)
		(property "Datasheet" "https://cdn.amphenol-cs.com/media/wysiwyg/files/drawing/g14a421x1bxxxhr.pdf"
			(at 0 0 0)
			(layer "F.Fab")
			(hide yes)
			(effects
				(font
					(size 1.27 1.27)
					(thickness 0.15)
				)
			)
		)
		(property "Description" "I/O Connectors OCulink, Receptacle, 0.5mm pitch, 4X, R/A SMT with shell leg SMT type, 30U\" gold plating, LCP, black, T&R packing"
			(at 0 0 0)
			(layer "F.Fab")
			(hide yes)
			(effects
				(font
					(size 1.27 1.27)
					(thickness 0.15)
				)
			)
		)
		(property "Manufacturer" "Amphenol"
			(at 0 0 0)
			(unlocked yes)
			(layer "F.Fab")
			(hide yes)
			(effects
				(font
					(size 1 1)
					(thickness 0.15)
				)
			)
		)
		(property "MPN" "G14A421211112HR"
			(at 0 0 0)
			(unlocked yes)
			(layer "F.Fab")
			(hide yes)
			(effects
				(font
					(size 1 1)
					(thickness 0.15)
				)
			)
		)
		(property "Author" "Antmicro"
			(at 0 0 0)
			(unlocked yes)
			(layer "F.Fab")
			(hide yes)
			(effects
				(font
					(size 1 1)
					(thickness 0.15)
				)
			)
		)
		(property "License" "Apache-2.0"
			(at 0 0 0)
			(unlocked yes)
			(layer "F.Fab")
			(hide yes)
			(effects
				(font
					(size 1 1)
					(thickness 0.15)
				)
			)
		)
		(sheetname "Root")
		(sheetfile "jetson-orin-baseboard-oculink-expansion.kicad_sch")
		(solder_paste_margin -0.06)
		(attr smd)
		(fp_line
			(start -6.8 -0.4)
			(end -6.8 -3)
			(stroke
				(width 0.1)
				(type default)
			)
			(layer "F.SilkS")
		)
		(fp_line
			(start 6.8 -3)
			(end 6.8 -0.4)
			(stroke
				(width 0.1)
				(type default)
			)
			(layer "F.SilkS")
		)
		(fp_circle
			(center -5.3 -5.52)
			(end -5.25 -5.52)
			(stroke
				(width 0.15)
				(type solid)
			)
			(fill solid)
			(layer "F.SilkS")
		)
		(fp_rect
			(start -8.22 -5.22)
			(end 8.22 4.94)
			(stroke
				(width 0.05)
				(type solid)
			)
			(fill none)
			(layer "F.CrtYd")
		)
		(fp_line
			(start 7 3.065)
			(end -7 3.065)
			(stroke
				(width 0.1)
				(type default)
			)
			(layer "F.Fab")
		)
		(fp_text user "Author: Antmicro"
			(at -8.22 11.085 0)
			(layer "F.Fab")
			(hide yes)
			(effects
				(font
					(size 0.7 0.7)
					(thickness 0.15)
				)
				(justify left bottom)
			)
		)
		(fp_text user "License: Apache-2.0"
			(at -8.22 12.285 0)
			(layer "F.Fab")
			(hide yes)
			(effects
				(font
					(size 0.7 0.7)
					(thickness 0.15)
				)
				(justify left bottom)
			)
		)
		(fp_text user "PCB EDGE"
			(at 2.8 2.95 0)
			(unlocked yes)
			(layer "F.Fab")
			(effects
				(font
					(size 0.5 0.5)
					(thickness 0.125)
				)
				(justify left bottom)
			)
		)
		(fp_text user "${REFERENCE}"
			(at -8.22 9.885 0)
			(unlocked yes)
			(layer "F.Fab")
			(hide yes)
			(effects
				(font
					(size 0.7 0.7)
					(thickness 0.15)
				)
				(justify left bottom)
			)
		)
		(pad "" np_thru_hole circle
			(at -5.42 -1.395 90)
			(size 1 1)
			(drill 1)
			(layers "F&B.Cu" "*.Mask")
		)
		(pad "" np_thru_hole circle
			(at 5.95 -1.395 90)
			(size 1 1)
			(drill 1)
			(layers "F&B.Cu" "*.Mask")
		)
		(pad "A1" smd roundrect
			(at -4.75 -2.115 90)
			(size 0.91 0.31)
			(layers "F.Cu" "F.Paste" "F.Mask")
			(roundrect_rratio 0.5)
			(net 132 "+3V3_OCU")
			(pinfunction "V_{ACT}_RX_3V3")
			(pintype "power_in")
		)
		(pad "A2" smd roundrect
			(at -4.25 -2.115 90)
			(size 0.91 0.31)
			(layers "F.Cu" "F.Paste" "F.Mask")
			(roundrect_rratio 0.5)
			(net 51 "GND")
			(pinfunction "GND")
			(pintype "passive")
		)
		(pad "A3" smd roundrect
			(at -3.75 -2.115 90)
			(size 0.91 0.31)
			(layers "F.Cu" "F.Paste" "F.Mask")
			(roundrect_rratio 0.5)
			(net 81 "/PCIE_{O}_RX0+")
			(pinfunction "PER0+")
			(pintype "output")
		)
		(pad "A4" smd roundrect
			(at -3.25 -2.115 90)
			(size 0.91 0.31)
			(layers "F.Cu" "F.Paste" "F.Mask")
			(roundrect_rratio 0.5)
			(net 83 "/PCIE_{O}_RX0-")
			(pinfunction "PER0-")
			(pintype "output")
		)
		(pad "A5" smd roundrect
			(at -2.75 -2.115 90)
			(size 0.91 0.31)
			(layers "F.Cu" "F.Paste" "F.Mask")
			(roundrect_rratio 0.5)
			(net 51 "GND")
			(pinfunction "GND")
			(pintype "passive")
		)
		(pad "A6" smd roundrect
			(at -2.25 -2.115 90)
			(size 0.91 0.31)
			(layers "F.Cu" "F.Paste" "F.Mask")
			(roundrect_rratio 0.5)
			(net 82 "/PCIE_{O}_RX1+")
			(pinfunction "PER1+")
			(pintype "output")
		)
		(pad "A7" smd roundrect
			(at -1.75 -2.115 90)
			(size 0.91 0.31)
			(layers "F.Cu" "F.Paste" "F.Mask")
			(roundrect_rratio 0.5)
			(net 84 "/PCIE_{O}_RX1-")
			(pinfunction "PER1-")
			(pintype "output")
		)
		(pad "A8" smd roundrect
			(at -1.25 -2.115 90)
			(size 0.91 0.31)
			(layers "F.Cu" "F.Paste" "F.Mask")
			(roundrect_rratio 0.5)
			(net 51 "GND")
			(pinfunction "GND")
			(pintype "passive")
		)
		(pad "A9" smd roundrect
			(at -0.75 -2.115 90)
			(size 0.91 0.31)
			(layers "F.Cu" "F.Paste" "F.Mask")
			(roundrect_rratio 0.5)
			(net 6 "unconnected-(J1-NC-PadA9)")
			(pinfunction "NC")
			(pintype "no_connect")
		)
		(pad "A10" smd roundrect
			(at -0.25 -2.115 90)
			(size 0.91 0.31)
			(layers "F.Cu" "F.Paste" "F.Mask")
			(roundrect_rratio 0.5)
			(net 54 "Net-(J1-~{CWAKE})")
			(pinfunction "~{CWAKE}")
			(pintype "bidirectional")
		)
		(pad "A11" smd roundrect
			(at 0.25 -2.115 90)
			(size 0.91 0.31)
			(layers "F.Cu" "F.Paste" "F.Mask")
			(roundrect_rratio 0.5)
			(net 51 "GND")
			(pinfunction "GND")
			(pintype "passive")
		)
		(pad "A12" smd roundrect
			(at 0.75 -2.115 90)
			(size 0.91 0.31)
			(layers "F.Cu" "F.Paste" "F.Mask")
			(roundrect_rratio 0.5)
			(net 53 "/PCIE_CLK+")
			(pinfunction "VSP1")
			(pintype "bidirectional")
		)
		(pad "A13" smd roundrect
			(at 1.25 -2.115 90)
			(size 0.91 0.31)
			(layers "F.Cu" "F.Paste" "F.Mask")
			(roundrect_rratio 0.5)
			(net 55 "/PCIE_CLK-")
			(pinfunction "VSP2")
			(pintype "bidirectional")
		)
		(pad "A14" smd roundrect
			(at 1.75 -2.115 90)
			(size 0.91 0.31)
			(layers "F.Cu" "F.Paste" "F.Mask")
			(roundrect_rratio 0.5)
			(net 51 "GND")
			(pinfunction "GND")
			(pintype "passive")
		)
		(pad "A15" smd roundrect
			(at 2.25 -2.115 90)
			(size 0.91 0.31)
			(layers "F.Cu" "F.Paste" "F.Mask")
			(roundrect_rratio 0.5)
			(net 5 "unconnected-(J1-PER2+-PadA15)")
			(pinfunction "PER2+")
			(pintype "output+no_connect")
		)
		(pad "A16" smd roundrect
			(at 2.75 -2.115 90)
			(size 0.91 0.31)
			(layers "F.Cu" "F.Paste" "F.Mask")
			(roundrect_rratio 0.5)
			(net 7 "unconnected-(J1-PER2--PadA16)")
			(pinfunction "PER2-")
			(pintype "output+no_connect")
		)
		(pad "A17" smd roundrect
			(at 3.25 -2.115 90)
			(size 0.91 0.31)
			(layers "F.Cu" "F.Paste" "F.Mask")
			(roundrect_rratio 0.5)
			(net 51 "GND")
			(pinfunction "GND")
			(pintype "passive")
		)
		(pad "A18" smd roundrect
			(at 3.75 -2.115 90)
			(size 0.91 0.31)
			(layers "F.Cu" "F.Paste" "F.Mask")
			(roundrect_rratio 0.5)
			(net 2 "unconnected-(J1-PER3+-PadA18)")
			(pinfunction "PER3+")
			(pintype "output+no_connect")
		)
		(pad "A19" smd roundrect
			(at 4.25 -2.115 90)
			(size 0.91 0.31)
			(layers "F.Cu" "F.Paste" "F.Mask")
			(roundrect_rratio 0.5)
			(net 3 "unconnected-(J1-PER3--PadA19)")
			(pinfunction "PER3-")
			(pintype "output+no_connect")
		)
		(pad "A20" smd roundrect
			(at 4.75 -2.115 90)
			(size 0.91 0.31)
			(layers "F.Cu" "F.Paste" "F.Mask")
			(roundrect_rratio 0.5)
			(net 51 "GND")
			(pinfunction "GND")
			(pintype "passive")
		)
		(pad "A21" smd roundrect
			(at 5.25 -2.115 90)
			(size 0.91 0.31)
			(layers "F.Cu" "F.Paste" "F.Mask")
			(roundrect_rratio 0.5)
			(net 133 "+5V_OCU")
			(pinfunction "5V")
			(pintype "passive")
		)
		(pad "B1" smd roundrect
			(at -5.25 -4.305 90)
			(size 0.91 0.31)
			(layers "F.Cu" "F.Paste" "F.Mask")
			(roundrect_rratio 0.5)
			(net 133 "+5V_OCU")
			(pinfunction "5V")
			(pintype "passive")
			(teardrops
				(best_length_ratio 0.5)
				(max_length 1)
				(best_width_ratio 1)
				(max_width 2)
				(curve_points 5)
				(filter_ratio 0.9)
				(enabled no)
				(allow_two_segments yes)
				(prefer_zone_connections yes)
			)
		)
		(pad "B2" smd roundrect
			(at -4.75 -4.305 90)
			(size 0.91 0.31)
			(layers "F.Cu" "F.Paste" "F.Mask")
			(roundrect_rratio 0.5)
			(net 51 "GND")
			(pinfunction "GND")
			(pintype "passive")
		)
		(pad "B3" smd roundrect
			(at -4.25 -4.305 90)
			(size 0.91 0.31)
			(layers "F.Cu" "F.Paste" "F.Mask")
			(roundrect_rratio 0.5)
			(net 72 "/PCIE_{O}_TX0+")
			(pinfunction "PET0+")
			(pintype "input")
		)
		(pad "B4" smd roundrect
			(at -3.75 -4.305 90)
			(size 0.91 0.31)
			(layers "F.Cu" "F.Paste" "F.Mask")
			(roundrect_rratio 0.5)
			(net 56 "/PCIE_{O}_TX0-")
			(pinfunction "PET0-")
			(pintype "input")
		)
		(pad "B5" smd roundrect
			(at -3.25 -4.305 90)
			(size 0.91 0.31)
			(layers "F.Cu" "F.Paste" "F.Mask")
			(roundrect_rratio 0.5)
			(net 51 "GND")
			(pinfunction "GND")
			(pintype "passive")
		)
		(pad "B6" smd roundrect
			(at -2.75 -4.305 90)
			(size 0.91 0.31)
			(layers "F.Cu" "F.Paste" "F.Mask")
			(roundrect_rratio 0.5)
			(net 58 "/PCIE_{O}_TX1+")
			(pinfunction "PET1+")
			(pintype "input")
		)
		(pad "B7" smd roundrect
			(at -2.25 -4.305 90)
			(size 0.91 0.31)
			(layers "F.Cu" "F.Paste" "F.Mask")
			(roundrect_rratio 0.5)
			(net 62 "/PCIE_{O}_TX1-")
			(pinfunction "PET1-")
			(pintype "input")
		)
		(pad "B8" smd roundrect
			(at -1.75 -4.305 90)
			(size 0.91 0.31)
			(layers "F.Cu" "F.Paste" "F.Mask")
			(roundrect_rratio 0.5)
			(net 51 "GND")
			(pinfunction "GND")
			(pintype "passive")
		)
		(pad "B9" smd roundrect
			(at -1.25 -4.305 90)
			(size 0.91 0.31)
			(layers "F.Cu" "F.Paste" "F.Mask")
			(roundrect_rratio 0.5)
			(net 126 "Net-(J1-SCL)")
			(pinfunction "SCL")
			(pintype "bidirectional")
		)
		(pad "B10" smd roundrect
			(at -0.75 -4.305 90)
			(size 0.91 0.31)
			(layers "F.Cu" "F.Paste" "F.Mask")
			(roundrect_rratio 0.5)
			(net 125 "Net-(J1-SDA)")
			(pinfunction "SDA")
			(pintype "bidirectional")
		)
		(pad "B11" smd roundrect
			(at -0.25 -4.305 90)
			(size 0.91 0.31)
			(layers "F.Cu" "F.Paste" "F.Mask")
			(roundrect_rratio 0.5)
			(net 51 "GND")
			(pinfunction "GND")
			(pintype "passive")
		)
		(pad "B12" smd roundrect
			(at 0.25 -4.305 90)
			(size 0.91 0.31)
			(layers "F.Cu" "F.Paste" "F.Mask")
			(roundrect_rratio 0.5)
			(net 59 "/~{PCIE_RST}")
			(pinfunction "~{PERST}")
			(pintype "bidirectional")
		)
		(pad "B13" smd roundrect
			(at 0.75 -4.305 90)
			(size 0.91 0.31)
			(layers "F.Cu" "F.Paste" "F.Mask")
			(roundrect_rratio 0.5)
			(net 66 "Net-(J1-~{CPRSNT})")
			(pinfunction "~{CPRSNT}")
			(pintype "bidirectional")
		)
		(pad "B14" smd roundrect
			(at 1.25 -4.305 90)
			(size 0.91 0.31)
			(layers "F.Cu" "F.Paste" "F.Mask")
			(roundrect_rratio 0.5)
			(net 51 "GND")
			(pinfunction "GND")
			(pintype "passive")
		)
		(pad "B15" smd roundrect
			(at 1.75 -4.305 90)
			(size 0.91 0.31)
			(layers "F.Cu" "F.Paste" "F.Mask")
			(roundrect_rratio 0.5)
			(net 4 "unconnected-(J1-PET2+-PadB15)")
			(pinfunction "PET2+")
			(pintype "input+no_connect")
		)
		(pad "B16" smd roundrect
			(at 2.25 -4.305 90)
			(size 0.91 0.31)
			(layers "F.Cu" "F.Paste" "F.Mask")
			(roundrect_rratio 0.5)
			(net 9 "unconnected-(J1-PET2--PadB16)")
			(pinfunction "PET2-")
			(pintype "input+no_connect")
		)
		(pad "B17" smd roundrect
			(at 2.75 -4.305 90)
			(size 0.91 0.31)
			(layers "F.Cu" "F.Paste" "F.Mask")
			(roundrect_rratio 0.5)
			(net 51 "GND")
			(pinfunction "GND")
			(pintype "passive")
		)
		(pad "B18" smd roundrect
			(at 3.25 -4.305 90)
			(size 0.91 0.31)
			(layers "F.Cu" "F.Paste" "F.Mask")
			(roundrect_rratio 0.5)
			(net 8 "unconnected-(J1-PET3+-PadB18)")
			(pinfunction "PET3+")
			(pintype "input+no_connect")
		)
		(pad "B19" smd roundrect
			(at 3.75 -4.305 90)
			(size 0.91 0.31)
			(layers "F.Cu" "F.Paste" "F.Mask")
			(roundrect_rratio 0.5)
			(net 1 "unconnected-(J1-PET3--PadB19)")
			(pinfunction "PET3-")
			(pintype "input+no_connect")
		)
		(pad "B20" smd roundrect
			(at 4.25 -4.305 90)
			(size 0.91 0.31)
			(layers "F.Cu" "F.Paste" "F.Mask")
			(roundrect_rratio 0.5)
			(net 51 "GND")
			(pinfunction "GND")
			(pintype "passive")
		)
		(pad "B21" smd roundrect
			(at 4.75 -4.305 90)
			(size 0.91 0.31)
			(layers "F.Cu" "F.Paste" "F.Mask")
			(roundrect_rratio 0.5)
			(net 132 "+3V3_OCU")
			(pinfunction "V_{ACT}_TX_3V3")
			(pintype "power_in")
		)
		(pad "SH" smd roundrect
			(at -6.91 -3.915 90)
			(size 1.38 1.81)
			(layers "F.Cu" "F.Paste" "F.Mask")
			(roundrect_rratio 0.1)
			(net 51 "GND")
			(pinfunction "SH")
			(pintype "passive")
		)
		(pad "SH" smd roundrect
			(at -6.91 0.805 90)
			(size 1.81 1.8)
			(layers "F.Cu" "F.Paste" "F.Mask")
			(roundrect_rratio 0.1)
			(net 51 "GND")
			(pinfunction "SH")
			(pintype "passive")
		)
		(pad "SH" smd roundrect
			(at 6.91 -3.915 90)
			(size 1.38 1.81)
			(layers "F.Cu" "F.Paste" "F.Mask")
			(roundrect_rratio 0.1)
			(net 51 "GND")
			(pinfunction "SH")
			(pintype "passive")
		)
		(pad "SH" smd roundrect
			(at 6.91 0.805 90)
			(size 1.81 1.8)
			(layers "F.Cu" "F.Paste" "F.Mask")
			(roundrect_rratio 0.1)
			(net 51 "GND")
			(pinfunction "SH")
			(pintype "passive")
		)
	)
	(footprint "antmicro-footprints:C_0402_1005Metric"
		(layer "F.Cu")
		(at 141.247 142.516 -90)
		(descr "Capacitor SMD 0402")
		(tags "capacitor SMD 0402")
		(property "Reference" "C6"
			(at -1.397 1.747 90)
			(layer "F.SilkS")
			(effects
				(font
					(size 0.7 0.7)
					(thickness 0.15)
				)
				(justify right top)
			)
		)
		(property "Value" "C_100n_0402"
			(at -1.022927 2.155213 90)
			(layer "F.Fab")
			(effects
				(font
					(size 0.7 0.7)
					(thickness 0.15)
				)
				(justify right top)
			)
		)
		(property "Footprint" "antmicro-footprints:C_0402_1005Metric"
			(at 0 0 90)
			(layer "F.Fab")
			(hide yes)
			(effects
				(font
					(size 1.27 1.27)
					(thickness 0.15)
				)
			)
		)
		(property "Datasheet" "https://www.murata.com/products/productdetail?partno=GRM155R61H104KE14%23"
			(at 0 0 90)
			(layer "F.Fab")
			(hide yes)
			(effects
				(font
					(size 1.27 1.27)
					(thickness 0.15)
				)
			)
		)
		(property "Description" "SMD Multilayer Ceramic Capacitor, 0.1 µF, 50 V, 0402 [1005 Metric], ± 10%, X5R, GRM Series"
			(at 0 0 90)
			(layer "F.Fab")
			(hide yes)
			(effects
				(font
					(size 1.27 1.27)
					(thickness 0.15)
				)
			)
		)
		(property "MPN" "GRM155R61H104KE14D"
			(at 0 0 -90)
			(unlocked yes)
			(layer "F.Fab")
			(hide yes)
			(effects
				(font
					(size 1 1)
					(thickness 0.15)
				)
			)
		)
		(property "Manufacturer" "Murata"
			(at 0 0 -90)
			(unlocked yes)
			(layer "F.Fab")
			(hide yes)
			(effects
				(font
					(size 1 1)
					(thickness 0.15)
				)
			)
		)
		(property "License" "Apache-2.0"
			(at 0 0 -90)
			(unlocked yes)
			(layer "F.Fab")
			(hide yes)
			(effects
				(font
					(size 1 1)
					(thickness 0.15)
				)
			)
		)
		(property "Author" "Antmicro"
			(at 0 0 -90)
			(unlocked yes)
			(layer "F.Fab")
			(hide yes)
			(effects
				(font
					(size 1 1)
					(thickness 0.15)
				)
			)
		)
		(property "Val" "100n"
			(at 0 0 -90)
			(unlocked yes)
			(layer "F.Fab")
			(hide yes)
			(effects
				(font
					(size 1 1)
					(thickness 0.15)
				)
			)
		)
		(property "Voltage" "50V"
			(at 0 0 -90)
			(unlocked yes)
			(layer "F.Fab")
			(hide yes)
			(effects
				(font
					(size 1 1)
					(thickness 0.15)
				)
			)
		)
		(property "Dielectric" "X5R"
			(at 0 0 -90)
			(unlocked yes)
			(layer "F.Fab")
			(hide yes)
			(effects
				(font
					(size 1 1)
					(thickness 0.15)
				)
			)
		)
		(sheetname "Root")
		(sheetfile "jetson-orin-baseboard-oculink-expansion.kicad_sch")
		(attr smd)
		(fp_rect
			(start -0.925 -0.47)
			(end 0.925 0.47)
			(stroke
				(width 0.05)
				(type default)
			)
			(fill none)
			(layer "F.CrtYd")
		)
		(fp_line
			(start -0.494 0.248)
			(end -0.494 -0.25)
			(stroke
				(width 0.15)
				(type solid)
			)
			(layer "F.Fab")
		)
		(fp_line
			(start 0.504 0.248)
			(end -0.494 0.248)
			(stroke
				(width 0.15)
				(type solid)
			)
			(layer "F.Fab")
		)
		(fp_line
			(start -0.494 -0.25)
			(end 0.504 -0.25)
			(stroke
				(width 0.15)
				(type solid)
			)
			(layer "F.Fab")
		)
		(fp_line
			(start 0.504 -0.25)
			(end 0.504 0.248)
			(stroke
				(width 0.15)
				(type solid)
			)
			(layer "F.Fab")
		)
		(fp_text user "${REFERENCE}"
			(at -0.939 4.599 90)
			(layer "F.Fab")
			(hide yes)
			(effects
				(font
					(size 0.7 0.7)
					(thickness 0.15)
				)
				(justify right top)
			)
		)
		(fp_text user "License: Apache-2.0"
			(at -0.939 5.799 90)
			(layer "F.Fab")
			(hide yes)
			(effects
				(font
					(size 0.7 0.7)
					(thickness 0.15)
				)
				(justify right top)
			)
		)
		(fp_text user "Author: Antmicro"
			(at -0.939 3.399 90)
			(layer "F.Fab")
			(hide yes)
			(effects
				(font
					(size 0.7 0.7)
					(thickness 0.15)
				)
				(justify right top)
			)
		)
		(pad "1" smd roundrect
			(at -0.48 0 270)
			(size 0.59 0.64)
			(layers "F.Cu" "F.Paste" "F.Mask")
			(roundrect_rratio 0.25)
			(net 51 "GND")
			(pintype "passive")
		)
		(pad "2" smd roundrect
			(at 0.48 0 270)
			(size 0.59 0.64)
			(layers "F.Cu" "F.Paste" "F.Mask")
			(roundrect_rratio 0.25)
			(net 23 "+3V3")
			(pintype "passive")
		)
	)
)
